FILE_TYPE = MACRO_DRAWING;
SET COLOR_WIRE YELLOW;
SET COLOR_PROP MONO;
SET COLOR_DOT WHITE;
SET COLOR_ARC YELLOW;
SET COLOR_BODY GREEN;
SET COLOR_NOTE MONO;
SET PROP_DISPLAY VALUE;
SET PAGE_NUMBER P16;
FORCEADD INTEL_CORP_BPAGE..1
(0 0);
FORCEPROP 1 LAST CUSTOM_TXT_CDS <CURRENT_DESIGN_SHEET> OF <TOTAL_DESIGN_SHEETS>
J 0
(-500 25);
PAINT GREEN (-500 25);
FORCEPROP 1 LAST CUSTOM_TXT_CDS <CON_LAST_MODIFIED>
J 0
(-1925 350);
PAINT GREEN (-1925 350);
FORCEPROP 2 LAST CUSTOM_TXT_CDS <XR_PAGE_TITLE>
J 0
(-7890 5250);
DISPLAY 0.638298 (-7890 5250);
PAINT PINK (-7890 5250);
DISPLAY INVISIBLE (-7890 5250);
FORCEPROP 1 LAST SCH_ADDRESS3 Santa Clara, CA 95052-8119
J 0
(-3975 25);
DISPLAY 0.617021 (-3975 25);
PAINT GREEN (-3975 25);
FORCEPROP 1 LAST SCH_ADDRESS2 P.O. BOX 58119
J 0
(-3975 75);
DISPLAY 0.617021 (-3975 75);
PAINT GREEN (-3975 75);
FORCEPROP 1 LAST SCH_ADDRESS1 2200 Mission College Blvd.
J 0
(-3975 125);
DISPLAY 0.617021 (-3975 125);
PAINT GREEN (-3975 125);
FORCEPROP 1 LAST SCH_TITLE POWER/RESET TIMING G3>S5
J 0
(-7950 50);
DISPLAY 1.212766 (-7950 50);
PAINT ORANGE (-7950 50);
FORCEPROP 1 LAST SCH_NUMBER H4694802
J 0
(-1300 150);
DISPLAY 1.212766 (-1300 150);
PAINT YELLOW (-1300 150);
FORCEPROP 1 LAST SCH_DEPT BESD
J 1
(-4450 100);
DISPLAY 1.212766 (-4450 100);
PAINT YELLOW (-4450 100);
FORCEPROP 1 LAST SCH_REV 2.420
J 0
(-250 150);
DISPLAY 0.978723 (-250 150);
PAINT YELLOW (-250 150);
FORCEPROP 2 LAST CDS_LIB mstr_symbols
J 0
(0 0);
PAINT MONO (0 0);
DISPLAY INVISIBLE (0 0);
FORCEPROP 2 LAST PAGE_BORDER TRUE
J 0
(-7890 5250);
DISPLAY 0.638298 (-7890 5250);
PAINT PINK (-7890 5250);
DISPLAY INVISIBLE (-7890 5250);
FORCEPROP 1 LAST COMMENT_BODY TRUE
J 0
(12 12);
DISPLAY 0.468085 (12 12);
PAINT GREEN (12 12);
DISPLAY INVISIBLE (12 12);
FORCEPROP 1 LAST CDS_CON_LAST_MODIFIED Tue Dec 01 11:47:58 2015
J 0
(-1425 325);
PAINT ORANGE (-1425 325);
DISPLAY INVISIBLE (-1425 325);
FORCEPROP 2 LAST CDS_XR_PAGE_TITLE CR-16 : @BASEBOARD_FAB2_LIB.BASEBOARD_FAB2(SCH_1):PAGE16
J 0
(-7890 5250);
DISPLAY 0.638298 (-7890 5250);
PAINT PINK (-7890 5250);
DISPLAY INVISIBLE (-7890 5250);
QUIT
